# SCM (Grand Teton) — schematic netlist excerpt (pin names and nets, part order shuffled) for the footprints in the layout excerpt that follows; sources: Cadence DE-HDL packaged netlist, KiCad conversion of 12092022_DA0F0TMDCD0_F0T_Management_Board_D_brd_V3_OCP.brd

R751  Q_RES  2K 1% CHIP  pkg 0402LF  page 22 : A = P3V3_AUX ; B = PWRGD_P1V0_AUX_DELAY_R1
R69  Q_RES  4.7K 1% CHIP  pkg 0402LF  page 11 : A = P3V3_AUX ; B = RST_SGPIO_RESET_N

(kicad_pcb
	(version 20260206)
	(generator "pcbnew")
	(generator_version "10.0")
	(general
		(thickness 1.6)
		(legacy_teardrops no)
	)
	(paper "A4")
	(title_block
		(title "12092022_DA0F0TMDCD0_F0T_Management_Board_D_brd_V3_OCP.brd")
		(comment 1 "Grand Teton / footprints 311-312 of 1440")
	)
	(layers
		(0 "F.Cu" signal "TOP")
		(4 "In1.Cu" signal "GND")
		(6 "In2.Cu" signal "IN1")
		(8 "In3.Cu" signal "GND1")
		(10 "In4.Cu" signal "IN2")
		(12 "In5.Cu" signal "VCC")
		(14 "In6.Cu" signal "VCC1")
		(16 "In7.Cu" signal "IN3")
		(18 "In8.Cu" signal "GND2")
		(20 "In9.Cu" signal "IN4")
		(22 "In10.Cu" signal "GND3")
		(2 "B.Cu" signal "BOTTOM")
		(9 "F.Adhes" user "F.Adhesive")
		(11 "B.Adhes" user "B.Adhesive")
		(13 "F.Paste" user "Package Geometry/Pastemask Top")
		(15 "B.Paste" user "Package Geometry/Pastemask Bottom")
		(5 "F.SilkS" user "Ref Des/Silkscreen Top")
		(7 "B.SilkS" user "Ref Des/Silkscreen Bottom")
		(1 "F.Mask" user "Board Geometry/Soldermask Top")
		(3 "B.Mask" user "Board Geometry/Soldermask Bottom")
		(17 "Dwgs.User" user "User.Drawings")
		(19 "Cmts.User" user "User.Comments")
		(21 "Eco1.User" user "User.Eco1")
		(23 "Eco2.User" user "User.Eco2")
		(25 "Edge.Cuts" user "Board Geometry/Outline")
		(27 "Margin" user)
		(31 "F.CrtYd" user "Package Geometry/Place Bound Top")
		(29 "B.CrtYd" user "Package Geometry/Place Bound Bottom")
		(35 "F.Fab" user "Ref Des/Assembly Top")
		(33 "B.Fab" user "Ref Des/Assembly Bottom")
	)
	(footprint ""
		(layer "F.Cu")
		(at 33.909 -36.195 90)
		(property "Reference" "R751"
			(at 0 0 90)
			(layer "F.SilkS")
			(hide yes)
			(effects
				(font
					(size 1.27 1.27)
				)
			)
		)
		(property "Value" ""
			(at 0 0 90)
			(layer "F.Fab")
			(effects
				(font
					(size 1.27 1.27)
				)
			)
		)
		(duplicate_pad_numbers_are_jumpers no)
		(fp_line
			(start 0.7874 -0.4064)
			(end 0.7874 0.4064)
			(stroke
				(width 0.1524)
				(type default)
			)
			(layer "F.SilkS")
		)
		(fp_line
			(start -0.7874 -0.4064)
			(end 0.7874 -0.4064)
			(stroke
				(width 0.1524)
				(type default)
			)
			(layer "F.SilkS")
		)
		(fp_line
			(start 0.7874 0.4064)
			(end -0.7874 0.4064)
			(stroke
				(width 0.1524)
				(type default)
			)
			(layer "F.SilkS")
		)
		(fp_line
			(start -0.7874 0.4064)
			(end -0.7874 -0.4064)
			(stroke
				(width 0.1524)
				(type default)
			)
			(layer "F.SilkS")
		)
		(fp_line
			(start -0.12065 -0.305054)
			(end -0.12065 -0.2794)
			(stroke
				(width 0.1)
				(type default)
			)
			(layer "F.Fab")
		)
		(fp_line
			(start -0.67945 -0.305054)
			(end -0.12065 -0.305054)
			(stroke
				(width 0.1)
				(type default)
			)
			(layer "F.Fab")
		)
		(fp_line
			(start 0.67945 -0.3048)
			(end 0.67945 0.3048)
			(stroke
				(width 0.1)
				(type default)
			)
			(layer "F.Fab")
		)
		(fp_line
			(start 0.12065 -0.3048)
			(end 0.67945 -0.3048)
			(stroke
				(width 0.1)
				(type default)
			)
			(layer "F.Fab")
		)
		(fp_line
			(start 0.12065 -0.2794)
			(end 0.12065 -0.3048)
			(stroke
				(width 0.1)
				(type default)
			)
			(layer "F.Fab")
		)
		(fp_line
			(start -0.12065 -0.2794)
			(end 0.12065 -0.2794)
			(stroke
				(width 0.1)
				(type default)
			)
			(layer "F.Fab")
		)
		(fp_line
			(start 0.120396 0.2794)
			(end -0.12065 0.2794)
			(stroke
				(width 0.1)
				(type default)
			)
			(layer "F.Fab")
		)
		(fp_line
			(start -0.12065 0.2794)
			(end -0.12065 0.3048)
			(stroke
				(width 0.1)
				(type default)
			)
			(layer "F.Fab")
		)
		(fp_line
			(start 0.67945 0.3048)
			(end 0.120396 0.3048)
			(stroke
				(width 0.1)
				(type default)
			)
			(layer "F.Fab")
		)
		(fp_line
			(start 0.120396 0.3048)
			(end 0.120396 0.2794)
			(stroke
				(width 0.1)
				(type default)
			)
			(layer "F.Fab")
		)
		(fp_line
			(start -0.12065 0.3048)
			(end -0.67945 0.3048)
			(stroke
				(width 0.1)
				(type default)
			)
			(layer "F.Fab")
		)
		(fp_line
			(start -0.67945 0.3048)
			(end -0.67945 -0.305054)
			(stroke
				(width 0.1)
				(type default)
			)
			(layer "F.Fab")
		)
		(pad "1" smd circle
			(at -0.40005 0 90)
			(size 0 0)
			(layers "F.Cu" "F.Mask" "F.Paste")
			(net "P3V3_AUX")
		)
		(pad "2" smd circle
			(at 0.40005 0 90)
			(size 0 0)
			(layers "F.Cu" "F.Mask" "F.Paste")
			(net "PWRGD_P1V0_AUX_DELAY_R1")
		)
	)
	(footprint ""
		(layer "F.Cu")
		(at 35.5346 -109.347 90)
		(property "Reference" "R69"
			(at 0 0 90)
			(layer "F.SilkS")
			(hide yes)
			(effects
				(font
					(size 1.27 1.27)
				)
			)
		)
		(property "Value" ""
			(at 0 0 90)
			(layer "F.Fab")
			(effects
				(font
					(size 1.27 1.27)
				)
			)
		)
		(duplicate_pad_numbers_are_jumpers no)
		(fp_line
			(start 0.7874 -0.4064)
			(end 0.7874 0.4064)
			(stroke
				(width 0.1524)
				(type default)
			)
			(layer "F.SilkS")
		)
		(fp_line
			(start -0.7874 -0.4064)
			(end 0.7874 -0.4064)
			(stroke
				(width 0.1524)
				(type default)
			)
			(layer "F.SilkS")
		)
		(fp_line
			(start 0.7874 0.4064)
			(end -0.7874 0.4064)
			(stroke
				(width 0.1524)
				(type default)
			)
			(layer "F.SilkS")
		)
		(fp_line
			(start -0.7874 0.4064)
			(end -0.7874 -0.4064)
			(stroke
				(width 0.1524)
				(type default)
			)
			(layer "F.SilkS")
		)
		(fp_line
			(start -0.12065 -0.305054)
			(end -0.12065 -0.2794)
			(stroke
				(width 0.1)
				(type default)
			)
			(layer "F.Fab")
		)
		(fp_line
			(start -0.67945 -0.305054)
			(end -0.12065 -0.305054)
			(stroke
				(width 0.1)
				(type default)
			)
			(layer "F.Fab")
		)
		(fp_line
			(start 0.67945 -0.3048)
			(end 0.67945 0.3048)
			(stroke
				(width 0.1)
				(type default)
			)
			(layer "F.Fab")
		)
		(fp_line
			(start 0.12065 -0.3048)
			(end 0.67945 -0.3048)
			(stroke
				(width 0.1)
				(type default)
			)
			(layer "F.Fab")
		)
		(fp_line
			(start 0.12065 -0.2794)
			(end 0.12065 -0.3048)
			(stroke
				(width 0.1)
				(type default)
			)
			(layer "F.Fab")
		)
		(fp_line
			(start -0.12065 -0.2794)
			(end 0.12065 -0.2794)
			(stroke
				(width 0.1)
				(type default)
			)
			(layer "F.Fab")
		)
		(fp_line
			(start 0.120396 0.2794)
			(end -0.12065 0.2794)
			(stroke
				(width 0.1)
				(type default)
			)
			(layer "F.Fab")
		)
		(fp_line
			(start -0.12065 0.2794)
			(end -0.12065 0.3048)
			(stroke
				(width 0.1)
				(type default)
			)
			(layer "F.Fab")
		)
		(fp_line
			(start 0.67945 0.3048)
			(end 0.120396 0.3048)
			(stroke
				(width 0.1)
				(type default)
			)
			(layer "F.Fab")
		)
		(fp_line
			(start 0.120396 0.3048)
			(end 0.120396 0.2794)
			(stroke
				(width 0.1)
				(type default)
			)
			(layer "F.Fab")
		)
		(fp_line
			(start -0.12065 0.3048)
			(end -0.67945 0.3048)
			(stroke
				(width 0.1)
				(type default)
			)
			(layer "F.Fab")
		)
		(fp_line
			(start -0.67945 0.3048)
			(end -0.67945 -0.305054)
			(stroke
				(width 0.1)
				(type default)
			)
			(layer "F.Fab")
		)
		(pad "1" smd circle
			(at -0.40005 0 90)
			(size 0 0)
			(layers "F.Cu" "F.Mask" "F.Paste")
			(net "P3V3_AUX")
		)
		(pad "2" smd circle
			(at 0.40005 0 90)
			(size 0 0)
			(layers "F.Cu" "F.Mask" "F.Paste")
			(net "RST_SGPIO_RESET_N")
		)
	)
)
